#ISCELL
  pure_quanta quanta_title_block_c *
  *
#ISCELL
  standard offpage *
  page216_i1
#CELL
  pure_quanta q_cap *
  page216_i10
#CELL
  pure_quanta q_cap *
  page216_i11
#ISCELL
  standard offpage *
  page216_i12
#ISCELL
  standard offpage *
  page216_i13
#ISCELL
  logical_power universal_power *
  page216_i14
#ISCELL
  logical_power universal_gnd *
  page216_i15
#ISCELL
  logical_power universal_gnd *
  page216_i16
#CELL
  pure_quanta q_cap *
  page216_i17
#ISCELL
  logical_power universal_power *
  page216_i18
#ISCELL
  logical_power universal_power *
  page216_i19
#ISCELL
  standard offpage *
  page216_i2
#ISCELL
  logical_power universal_power *
  page216_i20
#CELL
  pure_quanta q_res *
  page216_i21
#ISCELL
  standard offpage *
  page216_i22
#CELL
  pure_quanta q_cap *
  page216_i23
#ISCELL
  logical_power universal_gnd *
  page216_i24
#ISCELL
  standard offpage *
  page216_i25
#ISCELL
  standard offpage *
  page216_i26
#ISCELL
  standard offpage *
  page216_i27
#CELL
  pure_quanta pca9617adp *
  page216_i28
#ISCELL
  logical_power universal_power *
  page216_i29
#ISCELL
  logical_power universal_gnd *
  page216_i3
#CELL
  pure_quanta q_res *
  page216_i30
#CELL
  pure_quanta q_res *
  page216_i31
#ISCELL
  logical_power universal_power *
  page216_i32
#CELL
  pure_quanta q_res *
  page216_i33
#CELL
  pure_quanta q_res *
  page216_i34
#ISCELL
  logical_power universal_gnd *
  page216_i4
#CELL
  pure_quanta pca9617adp *
  page216_i5
#ISCELL
  logical_power universal_gnd *
  page216_i6
#CELL
  pure_quanta q_res *
  page216_i7
#ISCELL
  standard offpage *
  page216_i8
#ISCELL
  standard offpage *
  page216_i9
